FILE_TYPE=LIBRARY_PARTS;
TIME=' Created/Modified on Tue Dec 04 10:49:40 2007' ;
primitive 'Q_LED';
  pin
    'A':
      PIN_NUMBER='(A)';
      INPUT_LOAD='(-0.01,0.01)';
      OUTPUT_LOAD='(1.0,-1.0)';
      BIDIRECTIONAL='TRUE';
    'C':
      PIN_NUMBER='(C)';
      INPUT_LOAD='(-0.01,0.01)';
      OUTPUT_LOAD='(1.0,-1.0)';
      BIDIRECTIONAL='TRUE';
  end_pin;
  body
    CLASS='DISCRETE';
    PART_NAME='Q_LED';
    PHYS_DES_PREFIX='D';
  end_body;
end_primitive;
END.
